(kicad_pcb
	(version 20260206)
	(generator "pcbnew")
	(generator_version "10.0")
	(general
		(thickness 1.6)
		(legacy_teardrops no)
	)
	(paper "A4")
	(title_block
		(title "01162023_DA0F0TEBIF0_F0T_Expander_BD_F_brd_V02_OCP.brd")
		(comment 1 "Grand Teton / footprints 5958-5965 of 9728")
	)
	(layers
		(0 "F.Cu" signal "TOP")
		(4 "In1.Cu" signal "GND")
		(6 "In2.Cu" signal "VCC")
		(8 "In3.Cu" signal "VCC1")
		(10 "In4.Cu" signal "GND1")
		(12 "In5.Cu" signal "IN1")
		(14 "In6.Cu" signal "GND2")
		(16 "In7.Cu" signal "IN2")
		(18 "In8.Cu" signal "GND3")
		(20 "In9.Cu" signal "IN3")
		(22 "In10.Cu" signal "GND4")
		(24 "In11.Cu" signal "IN4")
		(26 "In12.Cu" signal "GND5")
		(28 "In13.Cu" signal "IN5")
		(30 "In14.Cu" signal "GND6")
		(32 "In15.Cu" signal "IN6")
		(34 "In16.Cu" signal "GND7")
		(2 "B.Cu" signal "BOTTOM")
		(9 "F.Adhes" user "F.Adhesive")
		(11 "B.Adhes" user "B.Adhesive")
		(13 "F.Paste" user "Package Geometry/Pastemask Top")
		(15 "B.Paste" user "Package Geometry/Pastemask Bottom")
		(5 "F.SilkS" user "Ref Des/Silkscreen Top")
		(7 "B.SilkS" user "Ref Des/Silkscreen Bottom")
		(1 "F.Mask" user "Board Geometry/Soldermask Top")
		(3 "B.Mask" user "Board Geometry/Soldermask Bottom")
		(17 "Dwgs.User" user "User.Drawings")
		(19 "Cmts.User" user "User.Comments")
		(21 "Eco1.User" user "User.Eco1")
		(23 "Eco2.User" user "User.Eco2")
		(25 "Edge.Cuts" user "Board Geometry/Outline")
		(27 "Margin" user)
		(31 "F.CrtYd" user "Package Geometry/Place Bound Top")
		(29 "B.CrtYd" user "Package Geometry/Place Bound Bottom")
		(35 "F.Fab" user "Ref Des/Assembly Top")
		(33 "B.Fab" user "Ref Des/Assembly Bottom")
	)
	(footprint ""
		(layer "F.Cu")
		(at 327.53173 -222.956882)
		(property "Reference" "R4172"
			(at 0 0 0)
			(layer "F.SilkS")
			(hide yes)
			(effects
				(font
					(size 1.27 1.27)
				)
			)
		)
		(property "Value" ""
			(at 0 0 0)
			(layer "F.Fab")
			(effects
				(font
					(size 1.27 1.27)
				)
			)
		)
		(duplicate_pad_numbers_are_jumpers no)
		(fp_line
			(start -0.7874 -0.4064)
			(end 0.7874 -0.4064)
			(stroke
				(width 0.1524)
				(type default)
			)
			(layer "F.SilkS")
		)
		(fp_line
			(start -0.7874 0.4064)
			(end -0.7874 -0.4064)
			(stroke
				(width 0.1524)
				(type default)
			)
			(layer "F.SilkS")
		)
		(fp_line
			(start 0.7874 -0.4064)
			(end 0.7874 0.4064)
			(stroke
				(width 0.1524)
				(type default)
			)
			(layer "F.SilkS")
		)
		(fp_line
			(start 0.7874 0.4064)
			(end -0.7874 0.4064)
			(stroke
				(width 0.1524)
				(type default)
			)
			(layer "F.SilkS")
		)
		(fp_line
			(start -0.67945 -0.305054)
			(end -0.12065 -0.305054)
			(stroke
				(width 0.1)
				(type default)
			)
			(layer "F.Fab")
		)
		(fp_line
			(start -0.67945 0.3048)
			(end -0.67945 -0.305054)
			(stroke
				(width 0.1)
				(type default)
			)
			(layer "F.Fab")
		)
		(fp_line
			(start -0.12065 -0.305054)
			(end -0.12065 -0.2794)
			(stroke
				(width 0.1)
				(type default)
			)
			(layer "F.Fab")
		)
		(fp_line
			(start -0.12065 -0.2794)
			(end 0.12065 -0.2794)
			(stroke
				(width 0.1)
				(type default)
			)
			(layer "F.Fab")
		)
		(fp_line
			(start -0.12065 0.2794)
			(end -0.12065 0.3048)
			(stroke
				(width 0.1)
				(type default)
			)
			(layer "F.Fab")
		)
		(fp_line
			(start -0.12065 0.3048)
			(end -0.67945 0.3048)
			(stroke
				(width 0.1)
				(type default)
			)
			(layer "F.Fab")
		)
		(fp_line
			(start 0.120396 0.2794)
			(end -0.12065 0.2794)
			(stroke
				(width 0.1)
				(type default)
			)
			(layer "F.Fab")
		)
		(fp_line
			(start 0.120396 0.3048)
			(end 0.120396 0.2794)
			(stroke
				(width 0.1)
				(type default)
			)
			(layer "F.Fab")
		)
		(fp_line
			(start 0.12065 -0.3048)
			(end 0.67945 -0.3048)
			(stroke
				(width 0.1)
				(type default)
			)
			(layer "F.Fab")
		)
		(fp_line
			(start 0.12065 -0.2794)
			(end 0.12065 -0.3048)
			(stroke
				(width 0.1)
				(type default)
			)
			(layer "F.Fab")
		)
		(fp_line
			(start 0.67945 -0.3048)
			(end 0.67945 0.3048)
			(stroke
				(width 0.1)
				(type default)
			)
			(layer "F.Fab")
		)
		(fp_line
			(start 0.67945 0.3048)
			(end 0.120396 0.3048)
			(stroke
				(width 0.1)
				(type default)
			)
			(layer "F.Fab")
		)
		(pad "1" smd circle
			(at -0.40005 0)
			(size 0 0)
			(layers "F.Cu" "F.Mask" "F.Paste")
			(net "RST_PEX1_PERST_R_N")
		)
		(pad "2" smd circle
			(at 0.40005 0)
			(size 0 0)
			(layers "F.Cu" "F.Mask" "F.Paste")
			(net "RST_PEX1_PERST_N")
		)
	)
	(footprint ""
		(layer "F.Cu")
		(at 312.857388 -112.504474 90)
		(property "Reference" "C921"
			(at 0 0 90)
			(layer "F.SilkS")
			(hide yes)
			(effects
				(font
					(size 1.27 1.27)
				)
			)
		)
		(property "Value" ""
			(at 0 0 90)
			(layer "F.Fab")
			(effects
				(font
					(size 1.27 1.27)
				)
			)
		)
		(duplicate_pad_numbers_are_jumpers no)
		(fp_line
			(start 1.524 -0.762)
			(end 1.524 0.762)
			(stroke
				(width 0.1524)
				(type default)
			)
			(layer "F.SilkS")
		)
		(fp_line
			(start -1.524 -0.762)
			(end 1.524 -0.762)
			(stroke
				(width 0.1524)
				(type default)
			)
			(layer "F.SilkS")
		)
		(fp_line
			(start 1.524 0.762)
			(end -1.524 0.762)
			(stroke
				(width 0.1524)
				(type default)
			)
			(layer "F.SilkS")
		)
		(fp_line
			(start -1.524 0.762)
			(end -1.524 -0.762)
			(stroke
				(width 0.1524)
				(type default)
			)
			(layer "F.SilkS")
		)
		(fp_line
			(start 1.1049 -0.724916)
			(end -1.1049 -0.724916)
			(stroke
				(width 0.1)
				(type default)
			)
			(layer "F.Fab")
		)
		(fp_line
			(start -1.1049 -0.724916)
			(end -1.1049 0.724916)
			(stroke
				(width 0.1)
				(type default)
			)
			(layer "F.Fab")
		)
		(fp_line
			(start 1.1049 0.724916)
			(end 1.1049 -0.724916)
			(stroke
				(width 0.1)
				(type default)
			)
			(layer "F.Fab")
		)
		(fp_line
			(start -1.1049 0.724916)
			(end 1.1049 0.724916)
			(stroke
				(width 0.1)
				(type default)
			)
			(layer "F.Fab")
		)
		(pad "1" smd rect
			(at -0.889 0 270)
			(size 1.016 1.27)
			(layers "F.Cu" "F.Mask" "F.Paste")
			(net "P12V_NIC5")
		)
		(pad "2" smd rect
			(at 0.889 0 270)
			(size 1.016 1.27)
			(layers "F.Cu" "F.Mask" "F.Paste")
			(net "GND")
		)
	)
	(footprint ""
		(layer "F.Cu")
		(at 195.432172 -32.848042 90)
		(property "Reference" "PC937"
			(at 0 0 90)
			(layer "F.SilkS")
			(hide yes)
			(effects
				(font
					(size 1.27 1.27)
				)
			)
		)
		(property "Value" ""
			(at 0 0 90)
			(layer "F.Fab")
			(effects
				(font
					(size 1.27 1.27)
				)
			)
		)
		(duplicate_pad_numbers_are_jumpers no)
		(fp_line
			(start 0.7874 -0.4064)
			(end 0.7874 0.4064)
			(stroke
				(width 0.1524)
				(type default)
			)
			(layer "F.SilkS")
		)
		(fp_line
			(start -0.7874 -0.4064)
			(end 0.7874 -0.4064)
			(stroke
				(width 0.1524)
				(type default)
			)
			(layer "F.SilkS")
		)
		(fp_line
			(start 0.7874 0.4064)
			(end -0.7874 0.4064)
			(stroke
				(width 0.1524)
				(type default)
			)
			(layer "F.SilkS")
		)
		(fp_line
			(start -0.7874 0.4064)
			(end -0.7874 -0.4064)
			(stroke
				(width 0.1524)
				(type default)
			)
			(layer "F.SilkS")
		)
		(fp_line
			(start -0.12065 -0.305054)
			(end -0.12065 -0.2794)
			(stroke
				(width 0.1)
				(type default)
			)
			(layer "F.Fab")
		)
		(fp_line
			(start -0.67945 -0.305054)
			(end -0.12065 -0.305054)
			(stroke
				(width 0.1)
				(type default)
			)
			(layer "F.Fab")
		)
		(fp_line
			(start 0.67945 -0.3048)
			(end 0.67945 0.3048)
			(stroke
				(width 0.1)
				(type default)
			)
			(layer "F.Fab")
		)
		(fp_line
			(start 0.12065 -0.3048)
			(end 0.67945 -0.3048)
			(stroke
				(width 0.1)
				(type default)
			)
			(layer "F.Fab")
		)
		(fp_line
			(start 0.12065 -0.2794)
			(end 0.12065 -0.3048)
			(stroke
				(width 0.1)
				(type default)
			)
			(layer "F.Fab")
		)
		(fp_line
			(start -0.12065 -0.2794)
			(end 0.12065 -0.2794)
			(stroke
				(width 0.1)
				(type default)
			)
			(layer "F.Fab")
		)
		(fp_line
			(start 0.120396 0.2794)
			(end -0.12065 0.2794)
			(stroke
				(width 0.1)
				(type default)
			)
			(layer "F.Fab")
		)
		(fp_line
			(start -0.12065 0.2794)
			(end -0.12065 0.3048)
			(stroke
				(width 0.1)
				(type default)
			)
			(layer "F.Fab")
		)
		(fp_line
			(start 0.67945 0.3048)
			(end 0.120396 0.3048)
			(stroke
				(width 0.1)
				(type default)
			)
			(layer "F.Fab")
		)
		(fp_line
			(start 0.120396 0.3048)
			(end 0.120396 0.2794)
			(stroke
				(width 0.1)
				(type default)
			)
			(layer "F.Fab")
		)
		(fp_line
			(start -0.12065 0.3048)
			(end -0.67945 0.3048)
			(stroke
				(width 0.1)
				(type default)
			)
			(layer "F.Fab")
		)
		(fp_line
			(start -0.67945 0.3048)
			(end -0.67945 -0.305054)
			(stroke
				(width 0.1)
				(type default)
			)
			(layer "F.Fab")
		)
		(pad "1" smd circle
			(at -0.40005 0 90)
			(size 0 0)
			(layers "F.Cu" "F.Mask" "F.Paste")
			(net "P3V3_SSD7_CO_DV_DT")
		)
		(pad "2" smd circle
			(at 0.40005 0 90)
			(size 0 0)
			(layers "F.Cu" "F.Mask" "F.Paste")
			(net "GND")
		)
	)
	(footprint ""
		(layer "F.Cu")
		(at 446.734438 -30.03169 180)
		(property "Reference" "C727"
			(at 0 0 180)
			(layer "F.SilkS")
			(hide yes)
			(effects
				(font
					(size 1.27 1.27)
				)
			)
		)
		(property "Value" ""
			(at 0 0 180)
			(layer "F.Fab")
			(effects
				(font
					(size 1.27 1.27)
				)
			)
		)
		(duplicate_pad_numbers_are_jumpers no)
		(fp_line
			(start 0.299974 0.150114)
			(end -0.299974 0.150114)
			(stroke
				(width 0.1)
				(type default)
			)
			(layer "F.Fab")
		)
		(fp_line
			(start 0.299974 -0.150114)
			(end 0.299974 0.150114)
			(stroke
				(width 0.1)
				(type default)
			)
			(layer "F.Fab")
		)
		(fp_line
			(start -0.299974 0.150114)
			(end -0.299974 -0.150114)
			(stroke
				(width 0.1)
				(type default)
			)
			(layer "F.Fab")
		)
		(fp_line
			(start -0.299974 -0.150114)
			(end 0.299974 -0.150114)
			(stroke
				(width 0.1)
				(type default)
			)
			(layer "F.Fab")
		)
		(pad "1" smd rect
			(at -0.2667 0 180)
			(size 0.3048 0.381)
			(layers "F.Cu" "F.Mask" "F.Paste")
			(net "P5E_PEX3_STN2_TX_DN<33>")
		)
		(pad "2" smd rect
			(at 0.2667 0 180)
			(size 0.3048 0.381)
			(layers "F.Cu" "F.Mask" "F.Paste")
			(net "P5E_PEX3_STN2_TX_C_DN<33>")
		)
	)
	(footprint ""
		(layer "F.Cu")
		(at 378.2949 -356.244906 90)
		(property "Reference" "C769"
			(at 0 0 90)
			(layer "F.SilkS")
			(hide yes)
			(effects
				(font
					(size 1.27 1.27)
				)
			)
		)
		(property "Value" ""
			(at 0 0 90)
			(layer "F.Fab")
			(effects
				(font
					(size 1.27 1.27)
				)
			)
		)
		(duplicate_pad_numbers_are_jumpers no)
		(fp_line
			(start 0.299974 -0.150114)
			(end 0.299974 0.150114)
			(stroke
				(width 0.1)
				(type default)
			)
			(layer "F.Fab")
		)
		(fp_line
			(start -0.299974 -0.150114)
			(end 0.299974 -0.150114)
			(stroke
				(width 0.1)
				(type default)
			)
			(layer "F.Fab")
		)
		(fp_line
			(start 0.299974 0.150114)
			(end -0.299974 0.150114)
			(stroke
				(width 0.1)
				(type default)
			)
			(layer "F.Fab")
		)
		(fp_line
			(start -0.299974 0.150114)
			(end -0.299974 -0.150114)
			(stroke
				(width 0.1)
				(type default)
			)
			(layer "F.Fab")
		)
		(pad "1" smd rect
			(at -0.2667 0 90)
			(size 0.3048 0.381)
			(layers "F.Cu" "F.Mask" "F.Paste")
			(net "P5E_PEX3_STN6_TX_DN<108>")
		)
		(pad "2" smd rect
			(at 0.2667 0 90)
			(size 0.3048 0.381)
			(layers "F.Cu" "F.Mask" "F.Paste")
			(net "P5E_PEX3_STN6_TX_C_DN<108>")
		)
	)
	(footprint ""
		(layer "F.Cu")
		(at 186.996832 -410.070554 180)
		(property "Reference" "Q125"
			(at 2.00406 -1.206754 90)
			(unlocked yes)
			(layer "F.SilkS")
			(effects
				(font
					(size 0.7874 0.5842)
					(thickness 0.1524)
				)
				(justify left)
			)
		)
		(property "Value" ""
			(at 0 0 180)
			(layer "F.Fab")
			(effects
				(font
					(size 1.27 1.27)
				)
			)
		)
		(duplicate_pad_numbers_are_jumpers no)
		(fp_line
			(start 1.335278 1.100074)
			(end 1.335278 -1.100074)
			(stroke
				(width 0.1524)
				(type default)
			)
			(layer "F.SilkS")
		)
		(fp_line
			(start 1.335278 -1.100074)
			(end -1.335278 -1.100074)
			(stroke
				(width 0.1524)
				(type default)
			)
			(layer "F.SilkS")
		)
		(fp_line
			(start -1.335278 1.100074)
			(end 1.335278 1.100074)
			(stroke
				(width 0.1524)
				(type default)
			)
			(layer "F.SilkS")
		)
		(fp_line
			(start -1.335278 -1.100074)
			(end -1.335278 1.100074)
			(stroke
				(width 0.1524)
				(type default)
			)
			(layer "F.SilkS")
		)
		(fp_line
			(start 0.674878 1.100074)
			(end 0.674878 -1.100074)
			(stroke
				(width 0.1)
				(type default)
			)
			(layer "F.Fab")
		)
		(fp_line
			(start 0.674878 -1.100074)
			(end -0.674878 -1.100074)
			(stroke
				(width 0.1)
				(type default)
			)
			(layer "F.Fab")
		)
		(fp_line
			(start -0.674878 1.100074)
			(end 0.674878 1.100074)
			(stroke
				(width 0.1)
				(type default)
			)
			(layer "F.Fab")
		)
		(fp_line
			(start -0.674878 -1.100074)
			(end -0.674878 1.100074)
			(stroke
				(width 0.1)
				(type default)
			)
			(layer "F.Fab")
		)
		(pad "D" smd rect
			(at 0.8001 0 90)
			(size 0.6096 0.8128)
			(layers "F.Cu" "F.Mask" "F.Paste")
			(net "HSC_UV_N")
		)
		(pad "G" smd rect
			(at -0.8001 -0.649986 90)
			(size 0.6096 0.8128)
			(layers "F.Cu" "F.Mask" "F.Paste")
			(net "A_P12V_AUX_FPH_GATE")
		)
		(pad "S" smd rect
			(at -0.8001 0.649986 90)
			(size 0.6096 0.8128)
			(layers "F.Cu" "F.Mask" "F.Paste")
			(net "GND")
		)
	)
	(footprint ""
		(layer "F.Cu")
		(at 294.76319 -195.362068 90)
		(property "Reference" "R3392"
			(at 0 0 90)
			(layer "F.SilkS")
			(hide yes)
			(effects
				(font
					(size 1.27 1.27)
				)
			)
		)
		(property "Value" ""
			(at 0 0 90)
			(layer "F.Fab")
			(effects
				(font
					(size 1.27 1.27)
				)
			)
		)
		(duplicate_pad_numbers_are_jumpers no)
		(fp_line
			(start 0.7874 -0.4064)
			(end 0.7874 0.4064)
			(stroke
				(width 0.1524)
				(type default)
			)
			(layer "F.SilkS")
		)
		(fp_line
			(start -0.7874 -0.4064)
			(end 0.7874 -0.4064)
			(stroke
				(width 0.1524)
				(type default)
			)
			(layer "F.SilkS")
		)
		(fp_line
			(start 0.7874 0.4064)
			(end -0.7874 0.4064)
			(stroke
				(width 0.1524)
				(type default)
			)
			(layer "F.SilkS")
		)
		(fp_line
			(start -0.7874 0.4064)
			(end -0.7874 -0.4064)
			(stroke
				(width 0.1524)
				(type default)
			)
			(layer "F.SilkS")
		)
		(fp_line
			(start -0.12065 -0.305054)
			(end -0.12065 -0.2794)
			(stroke
				(width 0.1)
				(type default)
			)
			(layer "F.Fab")
		)
		(fp_line
			(start -0.67945 -0.305054)
			(end -0.12065 -0.305054)
			(stroke
				(width 0.1)
				(type default)
			)
			(layer "F.Fab")
		)
		(fp_line
			(start 0.67945 -0.3048)
			(end 0.67945 0.3048)
			(stroke
				(width 0.1)
				(type default)
			)
			(layer "F.Fab")
		)
		(fp_line
			(start 0.12065 -0.3048)
			(end 0.67945 -0.3048)
			(stroke
				(width 0.1)
				(type default)
			)
			(layer "F.Fab")
		)
		(fp_line
			(start 0.12065 -0.2794)
			(end 0.12065 -0.3048)
			(stroke
				(width 0.1)
				(type default)
			)
			(layer "F.Fab")
		)
		(fp_line
			(start -0.12065 -0.2794)
			(end 0.12065 -0.2794)
			(stroke
				(width 0.1)
				(type default)
			)
			(layer "F.Fab")
		)
		(fp_line
			(start 0.120396 0.2794)
			(end -0.12065 0.2794)
			(stroke
				(width 0.1)
				(type default)
			)
			(layer "F.Fab")
		)
		(fp_line
			(start -0.12065 0.2794)
			(end -0.12065 0.3048)
			(stroke
				(width 0.1)
				(type default)
			)
			(layer "F.Fab")
		)
		(fp_line
			(start 0.67945 0.3048)
			(end 0.120396 0.3048)
			(stroke
				(width 0.1)
				(type default)
			)
			(layer "F.Fab")
		)
		(fp_line
			(start 0.120396 0.3048)
			(end 0.120396 0.2794)
			(stroke
				(width 0.1)
				(type default)
			)
			(layer "F.Fab")
		)
		(fp_line
			(start -0.12065 0.3048)
			(end -0.67945 0.3048)
			(stroke
				(width 0.1)
				(type default)
			)
			(layer "F.Fab")
		)
		(fp_line
			(start -0.67945 0.3048)
			(end -0.67945 -0.305054)
			(stroke
				(width 0.1)
				(type default)
			)
			(layer "F.Fab")
		)
		(pad "1" smd circle
			(at -0.40005 0 90)
			(size 0 0)
			(layers "F.Cu" "F.Mask" "F.Paste")
			(net "SPI_BIC1_MOSI_R2")
		)
		(pad "2" smd circle
			(at 0.40005 0 90)
			(size 0 0)
			(layers "F.Cu" "F.Mask" "F.Paste")
			(net "SPI_BIC1_MOSI_R4")
		)
	)
	(footprint ""
		(layer "F.Cu")
		(at 130.38074 -118.378986 90)
		(property "Reference" "PC796"
			(at 0 0 90)
			(layer "F.SilkS")
			(hide yes)
			(effects
				(font
					(size 1.27 1.27)
				)
			)
		)
		(property "Value" ""
			(at 0 0 90)
			(layer "F.Fab")
			(effects
				(font
					(size 1.27 1.27)
				)
			)
		)
		(duplicate_pad_numbers_are_jumpers no)
		(fp_line
			(start 0.7874 -0.4064)
			(end 0.7874 0.4064)
			(stroke
				(width 0.1524)
				(type default)
			)
			(layer "F.SilkS")
		)
		(fp_line
			(start -0.7874 -0.4064)
			(end 0.7874 -0.4064)
			(stroke
				(width 0.1524)
				(type default)
			)
			(layer "F.SilkS")
		)
		(fp_line
			(start 0.7874 0.4064)
			(end -0.7874 0.4064)
			(stroke
				(width 0.1524)
				(type default)
			)
			(layer "F.SilkS")
		)
		(fp_line
			(start -0.7874 0.4064)
			(end -0.7874 -0.4064)
			(stroke
				(width 0.1524)
				(type default)
			)
			(layer "F.SilkS")
		)
		(fp_line
			(start -0.12065 -0.305054)
			(end -0.12065 -0.2794)
			(stroke
				(width 0.1)
				(type default)
			)
			(layer "F.Fab")
		)
		(fp_line
			(start -0.67945 -0.305054)
			(end -0.12065 -0.305054)
			(stroke
				(width 0.1)
				(type default)
			)
			(layer "F.Fab")
		)
		(fp_line
			(start 0.67945 -0.3048)
			(end 0.67945 0.3048)
			(stroke
				(width 0.1)
				(type default)
			)
			(layer "F.Fab")
		)
		(fp_line
			(start 0.12065 -0.3048)
			(end 0.67945 -0.3048)
			(stroke
				(width 0.1)
				(type default)
			)
			(layer "F.Fab")
		)
		(fp_line
			(start 0.12065 -0.2794)
			(end 0.12065 -0.3048)
			(stroke
				(width 0.1)
				(type default)
			)
			(layer "F.Fab")
		)
		(fp_line
			(start -0.12065 -0.2794)
			(end 0.12065 -0.2794)
			(stroke
				(width 0.1)
				(type default)
			)
			(layer "F.Fab")
		)
		(fp_line
			(start 0.120396 0.2794)
			(end -0.12065 0.2794)
			(stroke
				(width 0.1)
				(type default)
			)
			(layer "F.Fab")
		)
		(fp_line
			(start -0.12065 0.2794)
			(end -0.12065 0.3048)
			(stroke
				(width 0.1)
				(type default)
			)
			(layer "F.Fab")
		)
		(fp_line
			(start 0.67945 0.3048)
			(end 0.120396 0.3048)
			(stroke
				(width 0.1)
				(type default)
			)
			(layer "F.Fab")
		)
		(fp_line
			(start 0.120396 0.3048)
			(end 0.120396 0.2794)
			(stroke
				(width 0.1)
				(type default)
			)
			(layer "F.Fab")
		)
		(fp_line
			(start -0.12065 0.3048)
			(end -0.67945 0.3048)
			(stroke
				(width 0.1)
				(type default)
			)
			(layer "F.Fab")
		)
		(fp_line
			(start -0.67945 0.3048)
			(end -0.67945 -0.305054)
			(stroke
				(width 0.1)
				(type default)
			)
			(layer "F.Fab")
		)
		(pad "1" smd circle
			(at -0.40005 0 90)
			(size 0 0)
			(layers "F.Cu" "F.Mask" "F.Paste")
			(net "P3V3_NIC2_CO_DV_DT")
		)
		(pad "2" smd circle
			(at 0.40005 0 90)
			(size 0 0)
			(layers "F.Cu" "F.Mask" "F.Paste")
			(net "GND")
		)
	)
)
